FILE_TYPE = MULTI_PHYS_TABLE;
PART 'ADM4073'
{==========================================================================================================================================================================================================}
:PACK_TYPE | MATERIAL | PART_NUMBER      = EnvComp | PART_NUMBER  | JEDEC_TYPE | DESCRIPTION                 | HEIGHT     | COMPONENT_TYPE |  LPID  | SPEED_URL | Status |RPL| AML | Bus_Unit | Days ;
{==========================================================================================================================================================================================================}
'SM'       | 'IC'     | 'G12194-001' (!) = 'UNK;UNK;UNK;UNK;ok;CIP' | 'G12194-001' | 'SOT23_6A' | 'ADM4073 CURRENT SENSE AMP' | '0.057 IN' | 'SMALLSMT'     | '1387' | 'http://speed.intel.com:8081/speed/module/pdm/item/pdm_item_detail_direct.asp?item_cde=G12194-001&item_rev=01&url_param=unused' | 'Design' | 'NO' | '2' | 'SMO_IC' | '???' 
'SM'       | 'EMPTY'  | 'G12194-001' (!) = 'UNK;UNK;UNK;UNK;ok;CIP' | 'G12194-001' | 'SOT23_6A' | 'ADM4073 CURRENT SENSE AMP' | '0.057 IN' | 'SMALLSMT'     | '1387' | 'http://speed.intel.com:8081/speed/module/pdm/item/pdm_item_detail_direct.asp?item_cde=G12194-001&item_rev=01&url_param=unused' | 'Design' | 'NO' | '2' | 'SMO_IC' | '???' 
END_PART
END.
